# T6G (Grand Teton) — schematic netlist excerpt (pin names and nets, part order shuffled) for the footprints in the layout excerpt that follows; sources: Cadence DE-HDL packaged netlist, KiCad conversion of 04192023_DAF0TMB3IC0_F0TG_MB_C_brd_V02_OCP.brd

J122  CONN1_10165288101LF  CONN1_10165288-101LF IO  pkg CON_GUIDE-F1XG  page 230 : NC1 = NC

(kicad_pcb
	(version 20260206)
	(generator "pcbnew")
	(generator_version "10.0")
	(general
		(thickness 1.6)
		(legacy_teardrops no)
	)
	(paper "A4")
	(title_block
		(title "04192023_DAF0TMB3IC0_F0TG_MB_C_brd_V02_OCP.brd")
		(comment 1 "Grand Teton / footprints 753-753 of 8354")
	)
	(layers
		(0 "F.Cu" signal "TOP")
		(4 "In1.Cu" signal "GND")
		(6 "In2.Cu" signal "IN1")
		(8 "In3.Cu" signal "GND1")
		(10 "In4.Cu" signal "IN2")
		(12 "In5.Cu" signal "GND2")
		(14 "In6.Cu" signal "IN3")
		(16 "In7.Cu" signal "GND3")
		(18 "In8.Cu" signal "VCC")
		(20 "In9.Cu" signal "VCC1")
		(22 "In10.Cu" signal "GND4")
		(24 "In11.Cu" signal "IN4")
		(26 "In12.Cu" signal "GND5")
		(28 "In13.Cu" signal "IN5")
		(30 "In14.Cu" signal "GND6")
		(32 "In15.Cu" signal "IN6")
		(34 "In16.Cu" signal "GND7")
		(2 "B.Cu" signal "BOTTOM")
		(9 "F.Adhes" user "F.Adhesive")
		(11 "B.Adhes" user "B.Adhesive")
		(13 "F.Paste" user "Package Geometry/Pastemask Top")
		(15 "B.Paste" user "Package Geometry/Pastemask Bottom")
		(5 "F.SilkS" user "Ref Des/Silkscreen Top")
		(7 "B.SilkS" user "Ref Des/Silkscreen Bottom")
		(1 "F.Mask" user "Board Geometry/Soldermask Top")
		(3 "B.Mask" user "Board Geometry/Soldermask Bottom")
		(17 "Dwgs.User" user "User.Drawings")
		(19 "Cmts.User" user "User.Comments")
		(21 "Eco1.User" user "User.Eco1")
		(23 "Eco2.User" user "User.Eco2")
		(25 "Edge.Cuts" user "Board Geometry/Outline")
		(27 "Margin" user)
		(31 "F.CrtYd" user "Package Geometry/Place Bound Top")
		(29 "B.CrtYd" user "Package Geometry/Place Bound Bottom")
		(35 "F.Fab" user "Ref Des/Assembly Top")
		(33 "B.Fab" user "Ref Des/Assembly Bottom")
	)
	(footprint ""
		(layer "F.Cu")
		(at 359.774998 -431.360072 180)
		(property "Reference" "J122"
			(at 4.688332 -9.347962 90)
			(unlocked yes)
			(layer "F.SilkS")
			(effects
				(font
					(size 0.7874 0.5842)
					(thickness 0.1524)
				)
				(justify left)
			)
		)
		(property "Value" ""
			(at 0 0 180)
			(layer "F.Fab")
			(effects
				(font
					(size 1.27 1.27)
				)
			)
		)
		(duplicate_pad_numbers_are_jumpers no)
		(fp_line
			(start 3.525012 9.6139)
			(end 3.525012 -10.489946)
			(stroke
				(width 0.1524)
				(type default)
			)
			(layer "F.SilkS")
		)
		(fp_line
			(start 3.525012 -10.489946)
			(end -3.525012 -10.489946)
			(stroke
				(width 0.1524)
				(type default)
			)
			(layer "F.SilkS")
		)
		(fp_line
			(start -3.525012 6.408928)
			(end -3.525012 9.6139)
			(stroke
				(width 0.1524)
				(type default)
			)
			(layer "F.SilkS")
		)
		(fp_line
			(start -3.525012 -10.489946)
			(end -3.525012 1.836928)
			(stroke
				(width 0.1524)
				(type default)
			)
			(layer "F.SilkS")
		)
		(fp_line
			(start 3.525012 21.310092)
			(end 3.525012 -10.489946)
			(stroke
				(width 0.1)
				(type default)
			)
			(layer "F.Fab")
		)
		(fp_line
			(start 3.525012 -10.489946)
			(end -3.525012 -10.489946)
			(stroke
				(width 0.1)
				(type default)
			)
			(layer "F.Fab")
		)
		(fp_line
			(start -3.525012 21.310092)
			(end 3.525012 21.310092)
			(stroke
				(width 0.1)
				(type default)
			)
			(layer "F.Fab")
		)
		(fp_line
			(start -3.525012 -10.489946)
			(end -3.525012 21.310092)
			(stroke
				(width 0.1)
				(type default)
			)
			(layer "F.Fab")
		)
		(pad "" np_thru_hole circle
			(at 0 -6.620002 180)
			(size 3.175 3.175)
			(drill 3.175)
			(layers "*.Cu" "*.Mask")
			(clearance 0.381)
			(thermal_gap 0.381)
		)
		(pad "" np_thru_hole circle
			(at 0 0 180)
			(size 0 0)
			(drill 3.175)
			(layers "*.Cu" "*.Mask")
			(clearance 0)
		)
		(pad "" np_thru_hole circle
			(at 0 5.130038 180)
			(size 3.175 3.175)
			(drill 3.175)
			(layers "*.Cu" "*.Mask")
			(clearance 0.381)
			(thermal_gap 0.381)
		)
		(zone
			(layers "F.Cu" "B.Cu" "In1.Cu" "In2.Cu" "In3.Cu" "In4.Cu" "In5.Cu" "In6.Cu"
				"In7.Cu" "In8.Cu" "In9.Cu" "In10.Cu" "In11.Cu" "In12.Cu" "In13.Cu" "In14.Cu"
				"In15.Cu" "In16.Cu"
			)
			(hatch none 0.5)
			(connect_pads
				(clearance 0)
			)
			(min_thickness 0.25)
			(keepout
				(tracks not_allowed)
				(vias allowed)
				(pads allowed)
				(copperpour not_allowed)
				(footprints allowed)
			)
			(placement
				(enabled no)
				(sheetname "")
			)
			(fill
				(thermal_gap 0.5)
				(thermal_bridge_width 0.5)
				(island_removal_mode 0)
			)
			(polygon
				(pts
					(arc
						(start 361.870498 -436.49011)
						(mid 357.679498 -436.49011)
						(end 361.870498 -436.49011)
					)
				)
			)
		)
		(zone
			(layers "F.Cu" "B.Cu" "In1.Cu" "In2.Cu" "In3.Cu" "In4.Cu" "In5.Cu" "In6.Cu"
				"In7.Cu" "In8.Cu" "In9.Cu" "In10.Cu" "In11.Cu" "In12.Cu" "In13.Cu" "In14.Cu"
				"In15.Cu" "In16.Cu"
			)
			(hatch none 0.5)
			(connect_pads
				(clearance 0)
			)
			(min_thickness 0.25)
			(keepout
				(tracks not_allowed)
				(vias allowed)
				(pads allowed)
				(copperpour not_allowed)
				(footprints allowed)
			)
			(placement
				(enabled no)
				(sheetname "")
			)
			(fill
				(thermal_gap 0.5)
				(thermal_bridge_width 0.5)
				(island_removal_mode 0)
			)
			(polygon
				(pts
					(arc
						(start 361.870498 -424.74007)
						(mid 357.679498 -424.74007)
						(end 361.870498 -424.74007)
					)
				)
			)
		)
		(zone
			(layers "F.Cu" "B.Cu" "In1.Cu" "In2.Cu" "In3.Cu" "In4.Cu" "In5.Cu" "In6.Cu"
				"In7.Cu" "In8.Cu" "In9.Cu" "In10.Cu" "In11.Cu" "In12.Cu" "In13.Cu" "In14.Cu"
				"In15.Cu" "In16.Cu"
			)
			(hatch none 0.5)
			(connect_pads
				(clearance 0)
			)
			(min_thickness 0.25)
			(keepout
				(tracks not_allowed)
				(vias allowed)
				(pads allowed)
				(copperpour not_allowed)
				(footprints allowed)
			)
			(placement
				(enabled no)
				(sheetname "")
			)
			(fill
				(thermal_gap 0.5)
				(thermal_bridge_width 0.5)
				(island_removal_mode 0)
			)
			(polygon
				(pts
					(arc
						(start 363.394498 -431.360072)
						(mid 356.155498 -431.360072)
						(end 363.394498 -431.360072)
					)
				)
			)
		)
	)
)
